# S9S_MB_2U (Grand Teton) — schematic netlist excerpt (pin names and nets, part order shuffled) for the footprints in the layout excerpt that follows; sources: Cadence DE-HDL packaged netlist, KiCad conversion of 03242023_DA0F0TMBIJ0_F0T_Motherboard_J_brd_V01_OCP.brd

PR4258  Q_RES  499 1% CHIP  pkg 0402LF  page 297 : A = PVCCD_HV_CPU1 ; B = GND
PC2199  Q_CAPP  560UF 2.5V 20% OSCON  pkg THLF  page 294 : A = PVCCFA_EHV_CPU1 ; B = GND
R4479  Q_RES  33.2 1% CHIP  pkg 0402LF  page 211 : A = FM_9ZXL045_2_OE_N ; B = CLK_GPU_2_OE_N

(kicad_pcb
	(version 20260206)
	(generator "pcbnew")
	(generator_version "10.0")
	(general
		(thickness 1.6)
		(legacy_teardrops no)
	)
	(paper "A4")
	(title_block
		(title "03242023_DA0F0TMBIJ0_F0T_Motherboard_J_brd_V01_OCP.brd")
		(comment 1 "Grand Teton / footprints 3144-3146 of 6105")
	)
	(layers
		(0 "F.Cu" signal "TOP")
		(4 "In1.Cu" signal "GND")
		(6 "In2.Cu" signal "IN1")
		(8 "In3.Cu" signal "GND1")
		(10 "In4.Cu" signal "IN2")
		(12 "In5.Cu" signal "GND2")
		(14 "In6.Cu" signal "IN3")
		(16 "In7.Cu" signal "GND3")
		(18 "In8.Cu" signal "VCC")
		(20 "In9.Cu" signal "VCC1")
		(22 "In10.Cu" signal "GND4")
		(24 "In11.Cu" signal "IN4")
		(26 "In12.Cu" signal "GND5")
		(28 "In13.Cu" signal "IN5")
		(30 "In14.Cu" signal "GND6")
		(32 "In15.Cu" signal "IN6")
		(34 "In16.Cu" signal "GND7")
		(2 "B.Cu" signal "BOTTOM")
		(9 "F.Adhes" user "F.Adhesive")
		(11 "B.Adhes" user "B.Adhesive")
		(13 "F.Paste" user "Package Geometry/Pastemask Top")
		(15 "B.Paste" user "Package Geometry/Pastemask Bottom")
		(5 "F.SilkS" user "Ref Des/Silkscreen Top")
		(7 "B.SilkS" user "Ref Des/Silkscreen Bottom")
		(1 "F.Mask" user "Board Geometry/Soldermask Top")
		(3 "B.Mask" user "Board Geometry/Soldermask Bottom")
		(17 "Dwgs.User" user "User.Drawings")
		(19 "Cmts.User" user "User.Comments")
		(21 "Eco1.User" user "User.Eco1")
		(23 "Eco2.User" user "User.Eco2")
		(25 "Edge.Cuts" user "Board Geometry/Outline")
		(27 "Margin" user)
		(31 "F.CrtYd" user "Package Geometry/Place Bound Top")
		(29 "B.CrtYd" user "Package Geometry/Place Bound Bottom")
		(35 "F.Fab" user "Ref Des/Assembly Top")
		(33 "B.Fab" user "Ref Des/Assembly Bottom")
	)
	(footprint ""
		(layer "F.Cu")
		(at 68.644008 -177.905156 90)
		(property "Reference" "PC2199"
			(at 0 0 90)
			(layer "F.SilkS")
			(hide yes)
			(effects
				(font
					(size 1.27 1.27)
				)
			)
		)
		(property "Value" ""
			(at 0 0 90)
			(layer "F.Fab")
			(effects
				(font
					(size 1.27 1.27)
				)
			)
		)
		(duplicate_pad_numbers_are_jumpers no)
		(fp_line
			(start 2.750058 0.999998)
			(end -2.750058 0.999998)
			(stroke
				(width 0.1524)
				(type default)
			)
			(layer "F.SilkS")
		)
		(fp_circle
			(center 0 0.999998)
			(end 0 3.750056)
			(stroke
				(width 0.1524)
				(type default)
			)
			(fill no)
			(layer "F.SilkS")
		)
		(fp_poly
			(pts
				(arc
					(start 2.750058 0.999998)
					(mid 0 3.750056)
					(end -2.750058 0.999998)
				)
			)
			(stroke
				(width 0)
				(type default)
			)
			(fill yes)
			(layer "F.SilkS")
		)
		(fp_circle
			(center 0 0.999998)
			(end 0 3.750056)
			(stroke
				(width 0.1)
				(type default)
			)
			(fill no)
			(layer "F.Fab")
		)
		(pad "1" thru_hole rect
			(at 0 0 90)
			(size 1.5748 1.5748)
			(drill 1.0668)
			(layers "*.Cu" "*.Mask")
			(remove_unused_layers no)
			(net "PVCCFA_EHV_CPU1")
			(clearance 0)
			(padstack
				(mode front_inner_back)
				(layer "Inner"
					(shape circle)
					(size 1.5748 1.5748)
					(clearance 0)
				)
				(layer "B.Cu"
					(shape rect)
					(size 1.5748 1.5748)
					(clearance 0)
				)
			)
		)
		(pad "2" thru_hole circle
			(at 0 1.999996 90)
			(size 1.5748 1.5748)
			(drill 1.0668)
			(layers "*.Cu" "*.Mask")
			(remove_unused_layers no)
			(net "GND")
			(clearance 0)
		)
	)
	(footprint ""
		(layer "F.Cu")
		(at 63.034164 -160.997392 180)
		(property "Reference" "PR4258"
			(at 0 0 180)
			(layer "F.SilkS")
			(hide yes)
			(effects
				(font
					(size 1.27 1.27)
				)
			)
		)
		(property "Value" ""
			(at 0 0 180)
			(layer "F.Fab")
			(effects
				(font
					(size 1.27 1.27)
				)
			)
		)
		(duplicate_pad_numbers_are_jumpers no)
		(fp_line
			(start 0.7874 0.4064)
			(end -0.7874 0.4064)
			(stroke
				(width 0.1524)
				(type default)
			)
			(layer "F.SilkS")
		)
		(fp_line
			(start 0.7874 -0.4064)
			(end 0.7874 0.4064)
			(stroke
				(width 0.1524)
				(type default)
			)
			(layer "F.SilkS")
		)
		(fp_line
			(start -0.7874 0.4064)
			(end -0.7874 -0.4064)
			(stroke
				(width 0.1524)
				(type default)
			)
			(layer "F.SilkS")
		)
		(fp_line
			(start -0.7874 -0.4064)
			(end 0.7874 -0.4064)
			(stroke
				(width 0.1524)
				(type default)
			)
			(layer "F.SilkS")
		)
		(fp_line
			(start 0.67945 0.3048)
			(end 0.120396 0.3048)
			(stroke
				(width 0.1)
				(type default)
			)
			(layer "F.Fab")
		)
		(fp_line
			(start 0.67945 -0.3048)
			(end 0.67945 0.3048)
			(stroke
				(width 0.1)
				(type default)
			)
			(layer "F.Fab")
		)
		(fp_line
			(start 0.12065 -0.2794)
			(end 0.12065 -0.3048)
			(stroke
				(width 0.1)
				(type default)
			)
			(layer "F.Fab")
		)
		(fp_line
			(start 0.12065 -0.3048)
			(end 0.67945 -0.3048)
			(stroke
				(width 0.1)
				(type default)
			)
			(layer "F.Fab")
		)
		(fp_line
			(start 0.120396 0.3048)
			(end 0.120396 0.2794)
			(stroke
				(width 0.1)
				(type default)
			)
			(layer "F.Fab")
		)
		(fp_line
			(start 0.120396 0.2794)
			(end -0.12065 0.2794)
			(stroke
				(width 0.1)
				(type default)
			)
			(layer "F.Fab")
		)
		(fp_line
			(start -0.12065 0.3048)
			(end -0.67945 0.3048)
			(stroke
				(width 0.1)
				(type default)
			)
			(layer "F.Fab")
		)
		(fp_line
			(start -0.12065 0.2794)
			(end -0.12065 0.3048)
			(stroke
				(width 0.1)
				(type default)
			)
			(layer "F.Fab")
		)
		(fp_line
			(start -0.12065 -0.2794)
			(end 0.12065 -0.2794)
			(stroke
				(width 0.1)
				(type default)
			)
			(layer "F.Fab")
		)
		(fp_line
			(start -0.12065 -0.305054)
			(end -0.12065 -0.2794)
			(stroke
				(width 0.1)
				(type default)
			)
			(layer "F.Fab")
		)
		(fp_line
			(start -0.67945 0.3048)
			(end -0.67945 -0.305054)
			(stroke
				(width 0.1)
				(type default)
			)
			(layer "F.Fab")
		)
		(fp_line
			(start -0.67945 -0.305054)
			(end -0.12065 -0.305054)
			(stroke
				(width 0.1)
				(type default)
			)
			(layer "F.Fab")
		)
		(pad "1" smd circle
			(at -0.40005 0 180)
			(size 0 0)
			(layers "F.Cu" "F.Mask" "F.Paste")
			(net "PVCCD_HV_CPU1")
		)
		(pad "2" smd circle
			(at 0.40005 0 180)
			(size 0 0)
			(layers "F.Cu" "F.Mask" "F.Paste")
			(net "GND")
		)
	)
	(footprint ""
		(layer "F.Cu")
		(at 106.7181 -411.582108 180)
		(property "Reference" "R4479"
			(at 0 0 180)
			(layer "F.SilkS")
			(hide yes)
			(effects
				(font
					(size 1.27 1.27)
				)
			)
		)
		(property "Value" ""
			(at 0 0 180)
			(layer "F.Fab")
			(effects
				(font
					(size 1.27 1.27)
				)
			)
		)
		(duplicate_pad_numbers_are_jumpers no)
		(fp_line
			(start 0.7874 0.4064)
			(end -0.7874 0.4064)
			(stroke
				(width 0.1524)
				(type default)
			)
			(layer "F.SilkS")
		)
		(fp_line
			(start 0.7874 -0.4064)
			(end 0.7874 0.4064)
			(stroke
				(width 0.1524)
				(type default)
			)
			(layer "F.SilkS")
		)
		(fp_line
			(start -0.7874 0.4064)
			(end -0.7874 -0.4064)
			(stroke
				(width 0.1524)
				(type default)
			)
			(layer "F.SilkS")
		)
		(fp_line
			(start -0.7874 -0.4064)
			(end 0.7874 -0.4064)
			(stroke
				(width 0.1524)
				(type default)
			)
			(layer "F.SilkS")
		)
		(fp_line
			(start 0.67945 0.3048)
			(end 0.120396 0.3048)
			(stroke
				(width 0.1)
				(type default)
			)
			(layer "F.Fab")
		)
		(fp_line
			(start 0.67945 -0.3048)
			(end 0.67945 0.3048)
			(stroke
				(width 0.1)
				(type default)
			)
			(layer "F.Fab")
		)
		(fp_line
			(start 0.12065 -0.2794)
			(end 0.12065 -0.3048)
			(stroke
				(width 0.1)
				(type default)
			)
			(layer "F.Fab")
		)
		(fp_line
			(start 0.12065 -0.3048)
			(end 0.67945 -0.3048)
			(stroke
				(width 0.1)
				(type default)
			)
			(layer "F.Fab")
		)
		(fp_line
			(start 0.120396 0.3048)
			(end 0.120396 0.2794)
			(stroke
				(width 0.1)
				(type default)
			)
			(layer "F.Fab")
		)
		(fp_line
			(start 0.120396 0.2794)
			(end -0.12065 0.2794)
			(stroke
				(width 0.1)
				(type default)
			)
			(layer "F.Fab")
		)
		(fp_line
			(start -0.12065 0.3048)
			(end -0.67945 0.3048)
			(stroke
				(width 0.1)
				(type default)
			)
			(layer "F.Fab")
		)
		(fp_line
			(start -0.12065 0.2794)
			(end -0.12065 0.3048)
			(stroke
				(width 0.1)
				(type default)
			)
			(layer "F.Fab")
		)
		(fp_line
			(start -0.12065 -0.2794)
			(end 0.12065 -0.2794)
			(stroke
				(width 0.1)
				(type default)
			)
			(layer "F.Fab")
		)
		(fp_line
			(start -0.12065 -0.305054)
			(end -0.12065 -0.2794)
			(stroke
				(width 0.1)
				(type default)
			)
			(layer "F.Fab")
		)
		(fp_line
			(start -0.67945 0.3048)
			(end -0.67945 -0.305054)
			(stroke
				(width 0.1)
				(type default)
			)
			(layer "F.Fab")
		)
		(fp_line
			(start -0.67945 -0.305054)
			(end -0.12065 -0.305054)
			(stroke
				(width 0.1)
				(type default)
			)
			(layer "F.Fab")
		)
		(pad "1" smd circle
			(at -0.40005 0 180)
			(size 0 0)
			(layers "F.Cu" "F.Mask" "F.Paste")
			(net "FM_9ZXL045_2_OE_N")
		)
		(pad "2" smd circle
			(at 0.40005 0 180)
			(size 0 0)
			(layers "F.Cu" "F.Mask" "F.Paste")
			(net "CLK_GPU_2_OE_N")
		)
	)
)
